#ISCELL
  mstr_misc dns *
  *
#ISCELL
  mstr_symbols design_note *
  *
#ISCELL
  mstr_symbols intel_corp_bpage *
  *
#ISCELL
  mstr_standard offpage *
  page204_i1
#ISCELL
  mstr_symbols gnd *
  page204_i13
#CELL
  mstr_discrete cap *
  page204_i18
#CELL
  dev_discrete cap_a *
  page204_i19
#ISCELL
  mstr_standard offpage *
  page204_i2
#CELL
  mstr_discrete cap *
  page204_i22
#ISCELL
  mstr_standard offpage *
  page204_i3
#CELL
  mstr_discrete res *
  page204_i33
#CELL
  mstr_discrete cap *
  page204_i34
#CELL
  dev_discrete cap_a *
  page204_i35
#CELL
  mstr_discrete cap *
  page204_i36
#CELL
  mstr_discrete cap *
  page204_i37
#CELL
  mstr_discrete cap *
  page204_i38
#ISCELL
  mstr_symbols pvccin_cpu0 *
  page204_i4
#ISCELL
  mstr_standard offpage *
  page204_i40
#ISCELL
  mstr_symbols vcc_core *
  page204_i41
#CELL
  mstr_discrete cap *
  page204_i42
#ISCELL
  mstr_symbols gnd *
  page204_i43
#ISCELL
  mstr_symbols vcc_core *
  page204_i44
#CELL
  mstr_discrete res *
  page204_i45
#CELL
  mstr_discrete inductor *
  page204_i46
#CELL
  mstr_discrete capp *
  page204_i48
#ISCELL
  mstr_symbols gnd *
  page204_i49
#CELL
  mstr_discrete inductor *
  page204_i5
#CELL
  mstr_discrete capp *
  page204_i50
#CELL
  dev_discrete cap_a *
  page204_i51
#ISCELL
  mstr_symbols gnd *
  page204_i52
#CELL
  mstr_analog adm4073 *
  page204_i53
#ISCELL
  mstr_symbols gnd *
  page204_i54
#ISCELL
  mstr_standard offpage *
  page204_i55
#ISCELL
  mstr_standard offpage *
  page204_i56
#ISCELL
  mstr_standard offpage *
  page204_i57
#ISCELL
  mstr_symbols pvccin_cpu0 *
  page204_i58
#ISCELL
  mstr_symbols gnd *
  page204_i59
#CELL
  mstr_discrete res *
  page204_i60
#CELL
  mstr_discrete res *
  page204_i61
#CELL
  mstr_discrete res *
  page204_i62
#CELL
  mstr_discrete res *
  page204_i63
#CELL
  mstr_discrete res *
  page204_i64
#ISCELL
  mstr_standard offpage *
  page204_i65
#ISCELL
  mstr_standard offpage *
  page204_i66
#CELL
  mstr_discrete capp *
  page204_i67
#ISCELL
  mstr_symbols p12v_stby *
  page204_i68
#ISCELL
  mstr_symbols p5v_stby *
  page204_i69
#CELL
  dev_discrete cap_a *
  page204_i70
#CELL
  mstr_discrete ir354xx *
  page204_i71
#ISCELL
  mstr_symbols gnd *
  page204_i8
#CELL
  mstr_discrete res *
  page204_i83
#ISCELL
  mstr_symbols gnd *
  page204_i84
#CELL
  dev_discrete cap_a *
  page204_i85
#ISCELL
  mstr_symbols gnd *
  page204_i86
#CELL
  mstr_discrete cap *
  page204_i88
#ISCELL
  mstr_symbols gnd *
  page204_i89
#CELL
  dev_discrete cap_a *
  page204_i9
#CELL
  w_hdl sc2k2p50v3kx-gp *
  page204_i90
#CELL
  w_hdl 3d01r5f-gp *
  page204_i91
#ISCELL
  mstr_symbols gnd *
  page204_i92
#CELL
  mstr_discrete res *
  page204_i93
